# SCM (Grand Teton) — schematic netlist excerpt (pin names and nets, part order shuffled) for the footprints in the layout excerpt that follows; sources: Cadence DE-HDL packaged netlist, KiCad conversion of 12092022_DA0F0TMDCD0_F0T_Management_Board_D_brd_V3_OCP.brd

D2  Q_LED  IC  pkg SMLF  page 47 : A = LED_POSTCODE_2_R ; C = GND
R313  Q_RES  470K 1% CHIP  pkg 0402LF  page 22 : A = RST_BMC_SELF_HW_D ; B = GND

(kicad_pcb
	(version 20260206)
	(generator "pcbnew")
	(generator_version "10.0")
	(general
		(thickness 1.6)
		(legacy_teardrops no)
	)
	(paper "A4")
	(title_block
		(title "12092022_DA0F0TMDCD0_F0T_Management_Board_D_brd_V3_OCP.brd")
		(comment 1 "Grand Teton / footprints 641-642 of 1440")
	)
	(layers
		(0 "F.Cu" signal "TOP")
		(4 "In1.Cu" signal "GND")
		(6 "In2.Cu" signal "IN1")
		(8 "In3.Cu" signal "GND1")
		(10 "In4.Cu" signal "IN2")
		(12 "In5.Cu" signal "VCC")
		(14 "In6.Cu" signal "VCC1")
		(16 "In7.Cu" signal "IN3")
		(18 "In8.Cu" signal "GND2")
		(20 "In9.Cu" signal "IN4")
		(22 "In10.Cu" signal "GND3")
		(2 "B.Cu" signal "BOTTOM")
		(9 "F.Adhes" user "F.Adhesive")
		(11 "B.Adhes" user "B.Adhesive")
		(13 "F.Paste" user "Package Geometry/Pastemask Top")
		(15 "B.Paste" user "Package Geometry/Pastemask Bottom")
		(5 "F.SilkS" user "Ref Des/Silkscreen Top")
		(7 "B.SilkS" user "Ref Des/Silkscreen Bottom")
		(1 "F.Mask" user "Board Geometry/Soldermask Top")
		(3 "B.Mask" user "Board Geometry/Soldermask Bottom")
		(17 "Dwgs.User" user "User.Drawings")
		(19 "Cmts.User" user "User.Comments")
		(21 "Eco1.User" user "User.Eco1")
		(23 "Eco2.User" user "User.Eco2")
		(25 "Edge.Cuts" user "Board Geometry/Outline")
		(27 "Margin" user)
		(31 "F.CrtYd" user "Package Geometry/Place Bound Top")
		(29 "B.CrtYd" user "Package Geometry/Place Bound Bottom")
		(35 "F.Fab" user "Ref Des/Assembly Top")
		(33 "B.Fab" user "Ref Des/Assembly Bottom")
	)
	(footprint ""
		(layer "F.Cu")
		(at 75.646534 -28.196032 -90)
		(property "Reference" "D2"
			(at 2.282952 -8.41883 90)
			(unlocked yes)
			(layer "F.SilkS")
			(effects
				(font
					(size 0.7874 0.5842)
					(thickness 0.1524)
				)
				(justify left)
			)
		)
		(property "Value" ""
			(at 0 0 270)
			(layer "F.Fab")
			(effects
				(font
					(size 1.27 1.27)
				)
			)
		)
		(duplicate_pad_numbers_are_jumpers no)
		(fp_line
			(start -1.3208 0.5588)
			(end -1.3208 -0.5588)
			(stroke
				(width 0.1524)
				(type default)
			)
			(layer "F.SilkS")
		)
		(fp_line
			(start 1.3208 0.5588)
			(end -1.3208 0.5588)
			(stroke
				(width 0.1524)
				(type default)
			)
			(layer "F.SilkS")
		)
		(fp_line
			(start 1.6256 0.5588)
			(end 1.6256 -0.5588)
			(stroke
				(width 0.1524)
				(type default)
			)
			(layer "F.SilkS")
		)
		(fp_line
			(start 1.778 0.5588)
			(end 1.3208 0.5588)
			(stroke
				(width 0.1524)
				(type default)
			)
			(layer "F.SilkS")
		)
		(fp_line
			(start -1.3208 -0.5588)
			(end 1.3208 -0.5588)
			(stroke
				(width 0.1524)
				(type default)
			)
			(layer "F.SilkS")
		)
		(fp_line
			(start 1.3208 -0.5588)
			(end 1.3208 0.5588)
			(stroke
				(width 0.1524)
				(type default)
			)
			(layer "F.SilkS")
		)
		(fp_line
			(start 1.4732 -0.5588)
			(end 1.4732 0.5588)
			(stroke
				(width 0.1524)
				(type default)
			)
			(layer "F.SilkS")
		)
		(fp_line
			(start 1.778 -0.5588)
			(end 1.778 0.5588)
			(stroke
				(width 0.1524)
				(type default)
			)
			(layer "F.SilkS")
		)
		(fp_line
			(start 1.778 -0.5588)
			(end 1.3208 -0.5588)
			(stroke
				(width 0.1524)
				(type default)
			)
			(layer "F.SilkS")
		)
		(fp_line
			(start -1.235964 0.508)
			(end -1.1684 0.508)
			(stroke
				(width 0.1)
				(type default)
			)
			(layer "F.Fab")
		)
		(fp_line
			(start -1.1684 0.508)
			(end 1.1684 0.508)
			(stroke
				(width 0.1)
				(type default)
			)
			(layer "F.Fab")
		)
		(fp_line
			(start 1.1684 0.508)
			(end 1.236726 0.508)
			(stroke
				(width 0.1)
				(type default)
			)
			(layer "F.Fab")
		)
		(fp_line
			(start 1.236726 0.508)
			(end 1.236726 -0.508)
			(stroke
				(width 0.1)
				(type default)
			)
			(layer "F.Fab")
		)
		(fp_line
			(start -1.235964 -0.508)
			(end -1.235964 0.508)
			(stroke
				(width 0.1)
				(type default)
			)
			(layer "F.Fab")
		)
		(fp_line
			(start -1.1684 -0.508)
			(end -1.235964 -0.508)
			(stroke
				(width 0.1)
				(type default)
			)
			(layer "F.Fab")
		)
		(fp_line
			(start 1.1684 -0.508)
			(end -1.1684 -0.508)
			(stroke
				(width 0.1)
				(type default)
			)
			(layer "F.Fab")
		)
		(fp_line
			(start 1.236726 -0.508)
			(end 1.1684 -0.508)
			(stroke
				(width 0.1)
				(type default)
			)
			(layer "F.Fab")
		)
		(fp_text user "+"
			(at -0.861568 1.014984 90)
			(unlocked yes)
			(layer "F.SilkS")
			(effects
				(font
					(size 1.905 1.4224)
					(thickness 0.1524)
				)
				(justify left)
			)
		)
		(fp_text user "-"
			(at 1.678432 -1.055116 270)
			(unlocked yes)
			(layer "F.SilkS")
			(effects
				(font
					(size 1.905 1.4224)
					(thickness 0.1524)
				)
				(justify left)
			)
		)
		(fp_text user "+"
			(at -2.5654 -0.24765 270)
			(unlocked yes)
			(layer "F.Fab")
			(effects
				(font
					(size 1.905 1.4224)
					(thickness 0.1524)
				)
				(justify left)
			)
		)
		(fp_text user "-"
			(at 1.524 -0.24765 270)
			(unlocked yes)
			(layer "F.Fab")
			(effects
				(font
					(size 1.905 1.4224)
					(thickness 0.1524)
				)
				(justify left)
			)
		)
		(pad "A" smd rect
			(at -0.750062 0 270)
			(size 0.8128 0.8128)
			(layers "F.Cu" "F.Mask" "F.Paste")
			(net "LED_POSTCODE_2_R")
		)
		(pad "C" smd rect
			(at 0.750062 0 270)
			(size 0.8128 0.8128)
			(layers "F.Cu" "F.Mask" "F.Paste")
			(net "GND")
		)
	)
	(footprint ""
		(layer "F.Cu")
		(at 25.06472 -108.4453 90)
		(property "Reference" "R313"
			(at 0 0 90)
			(layer "F.SilkS")
			(hide yes)
			(effects
				(font
					(size 1.27 1.27)
				)
			)
		)
		(property "Value" ""
			(at 0 0 90)
			(layer "F.Fab")
			(effects
				(font
					(size 1.27 1.27)
				)
			)
		)
		(duplicate_pad_numbers_are_jumpers no)
		(fp_line
			(start 0.7874 -0.4064)
			(end 0.7874 0.4064)
			(stroke
				(width 0.1524)
				(type default)
			)
			(layer "F.SilkS")
		)
		(fp_line
			(start -0.7874 -0.4064)
			(end 0.7874 -0.4064)
			(stroke
				(width 0.1524)
				(type default)
			)
			(layer "F.SilkS")
		)
		(fp_line
			(start 0.7874 0.4064)
			(end -0.7874 0.4064)
			(stroke
				(width 0.1524)
				(type default)
			)
			(layer "F.SilkS")
		)
		(fp_line
			(start -0.7874 0.4064)
			(end -0.7874 -0.4064)
			(stroke
				(width 0.1524)
				(type default)
			)
			(layer "F.SilkS")
		)
		(fp_line
			(start -0.12065 -0.305054)
			(end -0.12065 -0.2794)
			(stroke
				(width 0.1)
				(type default)
			)
			(layer "F.Fab")
		)
		(fp_line
			(start -0.67945 -0.305054)
			(end -0.12065 -0.305054)
			(stroke
				(width 0.1)
				(type default)
			)
			(layer "F.Fab")
		)
		(fp_line
			(start 0.67945 -0.3048)
			(end 0.67945 0.3048)
			(stroke
				(width 0.1)
				(type default)
			)
			(layer "F.Fab")
		)
		(fp_line
			(start 0.12065 -0.3048)
			(end 0.67945 -0.3048)
			(stroke
				(width 0.1)
				(type default)
			)
			(layer "F.Fab")
		)
		(fp_line
			(start 0.12065 -0.2794)
			(end 0.12065 -0.3048)
			(stroke
				(width 0.1)
				(type default)
			)
			(layer "F.Fab")
		)
		(fp_line
			(start -0.12065 -0.2794)
			(end 0.12065 -0.2794)
			(stroke
				(width 0.1)
				(type default)
			)
			(layer "F.Fab")
		)
		(fp_line
			(start 0.120396 0.2794)
			(end -0.12065 0.2794)
			(stroke
				(width 0.1)
				(type default)
			)
			(layer "F.Fab")
		)
		(fp_line
			(start -0.12065 0.2794)
			(end -0.12065 0.3048)
			(stroke
				(width 0.1)
				(type default)
			)
			(layer "F.Fab")
		)
		(fp_line
			(start 0.67945 0.3048)
			(end 0.120396 0.3048)
			(stroke
				(width 0.1)
				(type default)
			)
			(layer "F.Fab")
		)
		(fp_line
			(start 0.120396 0.3048)
			(end 0.120396 0.2794)
			(stroke
				(width 0.1)
				(type default)
			)
			(layer "F.Fab")
		)
		(fp_line
			(start -0.12065 0.3048)
			(end -0.67945 0.3048)
			(stroke
				(width 0.1)
				(type default)
			)
			(layer "F.Fab")
		)
		(fp_line
			(start -0.67945 0.3048)
			(end -0.67945 -0.305054)
			(stroke
				(width 0.1)
				(type default)
			)
			(layer "F.Fab")
		)
		(pad "1" smd circle
			(at -0.40005 0 90)
			(size 0 0)
			(layers "F.Cu" "F.Mask" "F.Paste")
			(net "RST_BMC_SELF_HW_D")
		)
		(pad "2" smd circle
			(at 0.40005 0 90)
			(size 0 0)
			(layers "F.Cu" "F.Mask" "F.Paste")
			(net "GND")
		)
	)
)
